(kicad_pcb
	(version 20260206)
	(generator "pcbnew")
	(generator_version "10.0")
	(general
		(thickness 1.6)
		(legacy_teardrops no)
	)
	(paper "A4")
	(title_block
		(title "Bryce Canyon_R.DPB_16317-1_OCP.brd")
		(comment 1 "Bryce Canyon / footprints 924-926 of 2099")
	)
	(layers
		(0 "F.Cu" signal "TOP")
		(4 "In1.Cu" signal "L2GND")
		(6 "In2.Cu" signal "L3")
		(8 "In3.Cu" signal "L4VCC")
		(10 "In4.Cu" signal "L5VCC")
		(12 "In5.Cu" signal "L6")
		(14 "In6.Cu" signal "L7GND")
		(2 "B.Cu" signal "BOTTOM")
		(9 "F.Adhes" user "F.Adhesive")
		(11 "B.Adhes" user "B.Adhesive")
		(13 "F.Paste" user "Package Geometry/Pastemask Top")
		(15 "B.Paste" user "Package Geometry/Pastemask Bottom")
		(5 "F.SilkS" user "Ref Des/Silkscreen Top")
		(7 "B.SilkS" user "Ref Des/Silkscreen Bottom")
		(1 "F.Mask" user "Board Geometry/Soldermask Top")
		(3 "B.Mask" user "Board Geometry/Soldermask Bottom")
		(17 "Dwgs.User" user "User.Drawings")
		(19 "Cmts.User" user "User.Comments")
		(21 "Eco1.User" user "User.Eco1")
		(23 "Eco2.User" user "User.Eco2")
		(25 "Edge.Cuts" user "Board Geometry/Outline")
		(27 "Margin" user)
		(31 "F.CrtYd" user "Package Geometry/Place Bound Top")
		(29 "B.CrtYd" user "Package Geometry/Place Bound Bottom")
		(35 "F.Fab" user "Ref Des/Assembly Top")
		(33 "B.Fab" user "Ref Des/Assembly Bottom")
	)
	(footprint ""
		(layer "F.Cu")
		(at 363.855 -36.83 180)
		(property "Reference" "C434"
			(at 0 0 180)
			(layer "F.SilkS")
			(hide yes)
			(effects
				(font
					(size 1.27 1.27)
				)
			)
		)
		(property "Value" "SC10U16V6KX-2GP"
			(at -0.0762 -5.1308 180)
			(unlocked yes)
			(layer "F.Fab")
			(hide yes)
			(effects
				(font
					(size 1.016 1.016)
					(thickness 0.1524)
				)
			)
		)
		(property "Device Type" "C1206H71"
			(at -0.127 -6.6548 180)
			(unlocked yes)
			(layer "F.Fab")
			(hide yes)
			(effects
				(font
					(size 1.016 1.016)
					(thickness 0.1524)
				)
			)
		)
		(duplicate_pad_numbers_are_jumpers no)
		(fp_line
			(start 1.016 2.2352)
			(end -1.016 2.2352)
			(stroke
				(width 0.1524)
				(type default)
			)
			(layer "F.SilkS")
		)
		(fp_line
			(start 1.016 0.8382)
			(end 1.016 2.2352)
			(stroke
				(width 0.1524)
				(type default)
			)
			(layer "F.SilkS")
		)
		(fp_line
			(start 1.016 -2.2352)
			(end 1.016 -0.8382)
			(stroke
				(width 0.1524)
				(type default)
			)
			(layer "F.SilkS")
		)
		(fp_line
			(start -1.016 2.2352)
			(end -1.016 0.8382)
			(stroke
				(width 0.1524)
				(type default)
			)
			(layer "F.SilkS")
		)
		(fp_line
			(start -1.016 -0.8382)
			(end -1.016 -2.2352)
			(stroke
				(width 0.1524)
				(type default)
			)
			(layer "F.SilkS")
		)
		(fp_line
			(start -1.016 -2.2352)
			(end 1.016 -2.2352)
			(stroke
				(width 0.1524)
				(type default)
			)
			(layer "F.SilkS")
		)
		(fp_rect
			(start -1.0922 2.3114)
			(end 1.0922 -2.3114)
			(stroke
				(width 0)
				(type default)
			)
			(fill no)
			(layer "F.CrtYd")
		)
		(fp_poly
			(pts
				(xy 1.0922 -2.3114) (xy 1.0922 2.3114) (xy -1.0922 2.3114) (xy -1.0922 -2.3114)
			)
			(stroke
				(width 0)
				(type default)
			)
			(fill no)
			(layer "F.Fab")
		)
		(pad "1" smd rect
			(at 0 -1.397 180)
			(size 1.651 1.27)
			(layers "F.Cu" "F.Mask" "F.Paste")
			(net "P5V_HDD31")
		)
		(pad "2" smd rect
			(at 0 1.397 180)
			(size 1.651 1.27)
			(layers "F.Cu" "F.Mask" "F.Paste")
			(net "GND")
		)
	)
	(footprint ""
		(layer "F.Cu")
		(at 241.995452 -358.855772 90)
		(property "Reference" "R1048"
			(at 0 0 90)
			(layer "F.SilkS")
			(hide yes)
			(effects
				(font
					(size 1.27 1.27)
				)
			)
		)
		(property "Value" "49K9R2F-L-GP"
			(at 0.064008 -3.993896 90)
			(unlocked yes)
			(layer "F.Fab")
			(hide yes)
			(effects
				(font
					(size 1.016 1.016)
					(thickness 0.1524)
				)
			)
		)
		(property "Device Type" "R402H16"
			(at 0.064008 -5.517896 90)
			(unlocked yes)
			(layer "F.Fab")
			(hide yes)
			(effects
				(font
					(size 1.016 1.016)
					(thickness 0.1524)
				)
			)
		)
		(duplicate_pad_numbers_are_jumpers no)
		(fp_line
			(start 0.508 -0.9398)
			(end -0.508 -0.9398)
			(stroke
				(width 0.1524)
				(type default)
			)
			(layer "F.SilkS")
		)
		(fp_line
			(start -0.508 -0.9398)
			(end -0.508 0.9398)
			(stroke
				(width 0.1524)
				(type default)
			)
			(layer "F.SilkS")
		)
		(fp_rect
			(start -0.508 0.9398)
			(end 0.508 -0.9398)
			(stroke
				(width 0)
				(type default)
			)
			(fill no)
			(layer "F.CrtYd")
		)
		(fp_rect
			(start -0.508 0.9398)
			(end 0.508 -0.9398)
			(stroke
				(width 0)
				(type default)
			)
			(fill no)
			(layer "F.Fab")
		)
		(pad "1" smd custom
			(at 0 -0.4445 90)
			(size 0.1397 0.1397)
			(layers "F.Cu" "F.Mask" "F.Paste")
			(net "P12V_IN")
			(options
				(clearance outline)
				(anchor circle)
			)
			(primitives
				(gr_poly
					(pts
						(arc
							(start -0.1778 -0.2794)
							(mid -0.249642 -0.249642)
							(end -0.2794 -0.1778)
						)
						(arc
							(start -0.2794 0.1778)
							(mid -0.249642 0.249642)
							(end -0.1778 0.2794)
						)
						(arc
							(start 0.1778 0.2794)
							(mid 0.249642 0.249642)
							(end 0.2794 0.1778)
						)
						(arc
							(start 0.2794 -0.1778)
							(mid 0.249642 -0.249642)
							(end 0.1778 -0.2794)
						)
					)
					(width 0)
					(fill yes)
				)
			)
		)
		(pad "2" smd custom
			(at 0 0.4445 90)
			(size 0.1397 0.1397)
			(layers "F.Cu" "F.Mask" "F.Paste")
			(net "MB3_CM_OV_R")
			(options
				(clearance outline)
				(anchor circle)
			)
			(primitives
				(gr_poly
					(pts
						(arc
							(start -0.1778 -0.2794)
							(mid -0.249642 -0.249642)
							(end -0.2794 -0.1778)
						)
						(arc
							(start -0.2794 0.1778)
							(mid -0.249642 0.249642)
							(end -0.1778 0.2794)
						)
						(arc
							(start 0.1778 0.2794)
							(mid 0.249642 0.249642)
							(end 0.2794 0.1778)
						)
						(arc
							(start 0.2794 -0.1778)
							(mid 0.249642 -0.249642)
							(end 0.1778 -0.2794)
						)
					)
					(width 0)
					(fill yes)
				)
			)
		)
	)
	(footprint ""
		(layer "F.Cu")
		(at 451.749922 -28.910026 -90)
		(property "Reference" "HDDSAS34"
			(at 0 0 270)
			(layer "F.SilkS")
			(hide yes)
			(effects
				(font
					(size 1.27 1.27)
				)
			)
		)
		(property "Value" "SKT-SAS15P-14P-45-GP"
			(at -20.7645 -8.9789 270)
			(unlocked yes)
			(layer "F.Fab")
			(hide yes)
			(effects
				(font
					(size 1.016 1.016)
					(thickness 0.1524)
				)
			)
		)
		(property "Device Type" "10120818-001C-TRLF"
			(at -20.7645 -10.5029 270)
			(unlocked yes)
			(layer "F.Fab")
			(hide yes)
			(effects
				(font
					(size 1.016 1.016)
					(thickness 0.1524)
				)
			)
		)
		(duplicate_pad_numbers_are_jumpers no)
		(fp_line
			(start 1.651 4.2926)
			(end 1.651 3.0099)
			(stroke
				(width 0.1524)
				(type default)
			)
			(layer "F.SilkS")
		)
		(fp_line
			(start 8.509 4.2926)
			(end 1.651 4.2926)
			(stroke
				(width 0.1524)
				(type default)
			)
			(layer "F.SilkS")
		)
		(fp_line
			(start -23.4188 3.0099)
			(end -23.4188 -3.2512)
			(stroke
				(width 0.1524)
				(type default)
			)
			(layer "F.SilkS")
		)
		(fp_line
			(start 1.651 3.0099)
			(end -23.4188 3.0099)
			(stroke
				(width 0.1524)
				(type default)
			)
			(layer "F.SilkS")
		)
		(fp_line
			(start 8.509 3.0099)
			(end 8.509 4.2926)
			(stroke
				(width 0.1524)
				(type default)
			)
			(layer "F.SilkS")
		)
		(fp_line
			(start 23.4188 3.0099)
			(end 8.509 3.0099)
			(stroke
				(width 0.1524)
				(type default)
			)
			(layer "F.SilkS")
		)
		(fp_line
			(start -23.4188 -3.2512)
			(end 23.4188 -3.2512)
			(stroke
				(width 0.1524)
				(type default)
			)
			(layer "F.SilkS")
		)
		(fp_line
			(start 23.4188 -3.2512)
			(end 23.4188 3.0099)
			(stroke
				(width 0.1524)
				(type default)
			)
			(layer "F.SilkS")
		)
		(fp_line
			(start 15.5067 -3.3401)
			(end 16.2687 -3.3401)
			(stroke
				(width 0.3302)
				(type default)
			)
			(layer "F.SilkS")
		)
		(fp_poly
			(pts
				(xy 15.868904 -3.230372) (xy 16.503904 -3.865372) (xy 15.233904 -3.865372)
			)
			(stroke
				(width 0)
				(type default)
			)
			(fill yes)
			(layer "F.SilkS")
		)
		(fp_poly
			(pts
				(xy -22.8727 -2.7559) (xy 22.8727 -2.7559) (xy 22.8727 2.7559) (xy 8.255 2.7559) (xy 8.255 3.5179)
				(xy 1.905 3.5179) (xy 1.905 2.7559) (xy -22.8727 2.7559)
			)
			(stroke
				(width 0)
				(type default)
			)
			(fill no)
			(layer "F.CrtYd")
		)
		(fp_poly
			(pts
				(xy 1.397 4.5466) (xy 1.397 3.2639) (xy -23.6728 3.2639) (xy -23.6728 -3.5052) (xy 23.6728 -3.5052)
				(xy 23.6728 -0.00635) (xy 22.8727 -0.00635) (xy 22.8727 -2.7559) (xy -22.8727 -2.7559) (xy -22.8727 2.7559)
				(xy 1.905 2.7559) (xy 1.905 3.5179) (xy 8.255 3.5179) (xy 8.255 2.7559) (xy 22.8727 2.7559) (xy 22.8727 0.00635)
				(xy 23.6728 0.00635) (xy 23.6728 3.2639) (xy 8.763 3.2639) (xy 8.763 4.5466)
			)
			(stroke
				(width 0)
				(type default)
			)
			(fill no)
			(layer "F.CrtYd")
		)
		(fp_poly
			(pts
				(xy 1.397 4.5466) (xy 1.397 3.2639) (xy -23.6728 3.2639) (xy -23.6728 -3.5052) (xy 23.6728 -3.5052)
				(xy 23.6728 3.2639) (xy 8.763 3.2639) (xy 8.763 4.5466)
			)
			(stroke
				(width 0)
				(type default)
			)
			(fill no)
			(layer "F.Fab")
		)
		(pad "" np_thru_hole circle
			(at -18.874994 0 270)
			(size 0.254 0.254)
			(drill 1.3462)
			(layers "*.Cu" "*.Mask")
			(clearance 0.9017)
			(thermal_gap 0.9017)
		)
		(pad "" np_thru_hole circle
			(at 18.874994 0 270)
			(size 0.254 0.254)
			(drill 0.9398)
			(layers "*.Cu" "*.Mask")
			(clearance 0.6985)
			(thermal_gap 0.6985)
		)
		(pad "G1" smd rect
			(at 21.874988 0 270)
			(size 2.5908 2.5908)
			(layers "F.Cu" "F.Mask" "F.Paste")
			(net "GND")
		)
		(pad "G2" smd rect
			(at -21.874988 0 270)
			(size 2.5908 2.5908)
			(layers "F.Cu" "F.Mask" "F.Paste")
			(net "GND")
		)
		(pad "P1" smd rect
			(at 1.905 -1.82499 270)
			(size 0.6096 2.3622)
			(layers "F.Cu" "F.Mask" "F.Paste")
			(net "Net_1624")
		)
		(pad "P2" smd rect
			(at 0.635 -1.82499 270)
			(size 0.6096 2.3622)
			(layers "F.Cu" "F.Mask" "F.Paste")
			(net "Net_1625")
		)
		(pad "P3" smd rect
			(at -0.635 -1.82499 270)
			(size 0.6096 2.3622)
			(layers "F.Cu" "F.Mask" "F.Paste")
			(net "Net_1626")
		)
		(pad "P4" smd rect
			(at -1.905 -1.82499 270)
			(size 0.6096 2.3622)
			(layers "F.Cu" "F.Mask" "F.Paste")
			(net "GND")
		)
		(pad "P5" smd rect
			(at -3.175 -1.82499 270)
			(size 0.6096 2.3622)
			(layers "F.Cu" "F.Mask" "F.Paste")
			(net "HDD_PRSNT_34")
		)
		(pad "P6" smd rect
			(at -4.445 -1.82499 270)
			(size 0.6096 2.3622)
			(layers "F.Cu" "F.Mask" "F.Paste")
			(net "GND")
		)
		(pad "P7" smd rect
			(at -5.715 -1.82499 270)
			(size 0.6096 2.3622)
			(layers "F.Cu" "F.Mask" "F.Paste")
			(net "5V_PRE_34")
		)
		(pad "P8" smd rect
			(at -6.985 -1.82499 270)
			(size 0.6096 2.3622)
			(layers "F.Cu" "F.Mask" "F.Paste")
			(net "P5V_HDD34")
		)
		(pad "P9" smd rect
			(at -8.255 -1.82499 270)
			(size 0.6096 2.3622)
			(layers "F.Cu" "F.Mask" "F.Paste")
			(net "P5V_HDD34")
		)
		(pad "P10" smd rect
			(at -9.525 -1.82499 270)
			(size 0.6096 2.3622)
			(layers "F.Cu" "F.Mask" "F.Paste")
			(net "GND")
		)
		(pad "P11" smd rect
			(at -10.795 -1.82499 270)
			(size 0.6096 2.3622)
			(layers "F.Cu" "F.Mask" "F.Paste")
			(net "ACT_HDD_34")
		)
		(pad "P12" smd rect
			(at -12.065 -1.82499 270)
			(size 0.6096 2.3622)
			(layers "F.Cu" "F.Mask" "F.Paste")
			(net "GND")
		)
		(pad "P13" smd rect
			(at -13.335 -1.82499 270)
			(size 0.6096 2.3622)
			(layers "F.Cu" "F.Mask" "F.Paste")
			(net "12V_PRE_34")
		)
		(pad "P14" smd rect
			(at -14.605 -1.82499 270)
			(size 0.6096 2.3622)
			(layers "F.Cu" "F.Mask" "F.Paste")
			(net "P12V_HDD34")
		)
		(pad "P15" smd rect
			(at -15.875 -1.82499 270)
			(size 0.6096 2.3622)
			(layers "F.Cu" "F.Mask" "F.Paste")
			(net "P12V_HDD34")
		)
		(pad "S1" smd rect
			(at 15.875 -1.82499 270)
			(size 0.6096 2.3622)
			(layers "F.Cu" "F.Mask" "F.Paste")
			(net "GND")
		)
		(pad "S2" smd rect
			(at 14.605 -1.82499 270)
			(size 0.6096 2.3622)
			(layers "F.Cu" "F.Mask" "F.Paste")
			(net "SAS_HDD_RX_P34")
		)
		(pad "S3" smd rect
			(at 13.335 -1.82499 270)
			(size 0.6096 2.3622)
			(layers "F.Cu" "F.Mask" "F.Paste")
			(net "SAS_HDD_RX_N34")
		)
		(pad "S4" smd rect
			(at 12.065 -1.82499 270)
			(size 0.6096 2.3622)
			(layers "F.Cu" "F.Mask" "F.Paste")
			(net "GND")
		)
		(pad "S5" smd rect
			(at 10.795 -1.82499 270)
			(size 0.6096 2.3622)
			(layers "F.Cu" "F.Mask" "F.Paste")
			(net "PHY_DRV_B_TO_SCC_B_34_DN")
		)
		(pad "S6" smd rect
			(at 9.525 -1.82499 270)
			(size 0.6096 2.3622)
			(layers "F.Cu" "F.Mask" "F.Paste")
			(net "PHY_DRV_B_TO_SCC_B_34_DP")
		)
		(pad "S7" smd rect
			(at 8.255 -1.82499 270)
			(size 0.6096 2.3622)
			(layers "F.Cu" "F.Mask" "F.Paste")
			(net "GND")
		)
		(pad "S8" smd rect
			(at 7.480046 2.845054 270)
			(size 0.508 2.3622)
			(layers "F.Cu" "F.Mask" "F.Paste")
			(net "GND")
		)
		(pad "S9" smd rect
			(at 6.679946 2.845054 270)
			(size 0.508 2.3622)
			(layers "F.Cu" "F.Mask" "F.Paste")
			(net "Net_459")
		)
		(pad "S10" smd rect
			(at 5.8801 2.845054 270)
			(size 0.508 2.3622)
			(layers "F.Cu" "F.Mask" "F.Paste")
			(net "Net_351")
		)
		(pad "S11" smd rect
			(at 5.08 2.845054 270)
			(size 0.508 2.3622)
			(layers "F.Cu" "F.Mask" "F.Paste")
			(net "GND")
		)
		(pad "S12" smd rect
			(at 4.2799 2.845054 270)
			(size 0.508 2.3622)
			(layers "F.Cu" "F.Mask" "F.Paste")
			(net "Net_387")
		)
		(pad "S13" smd rect
			(at 3.480054 2.845054 270)
			(size 0.508 2.3622)
			(layers "F.Cu" "F.Mask" "F.Paste")
			(net "Net_423")
		)
		(pad "S14" smd rect
			(at 2.679954 2.845054 270)
			(size 0.508 2.3622)
			(layers "F.Cu" "F.Mask" "F.Paste")
			(net "GND")
		)
		(zone
			(layer "F.Cu")
			(hatch none 0.5)
			(connect_pads
				(clearance 0)
			)
			(min_thickness 0.25)
			(keepout
				(tracks not_allowed)
				(vias allowed)
				(pads allowed)
				(copperpour not_allowed)
				(footprints allowed)
			)
			(placement
				(enabled no)
				(sheetname "")
			)
			(fill
				(thermal_gap 0.5)
				(thermal_bridge_width 0.5)
				(island_removal_mode 0)
			)
			(polygon
				(pts
					(xy 455.407522 -45.648626) (xy 448.333622 -45.648626) (xy 448.333622 -52.582826) (xy 449.438522 -52.582826)
					(xy 449.438522 -48.468026) (xy 454.061322 -48.468026) (xy 454.061322 -52.582826) (xy 455.407522 -52.582826)
				)
			)
		)
		(zone
			(layer "F.Cu")
			(hatch none 0.5)
			(connect_pads
				(clearance 0)
			)
			(min_thickness 0.25)
			(keepout
				(tracks allowed)
				(vias not_allowed)
				(pads allowed)
				(copperpour not_allowed)
				(footprints allowed)
			)
			(placement
				(enabled no)
				(sheetname "")
			)
			(fill
				(thermal_gap 0.5)
				(thermal_bridge_width 0.5)
				(island_removal_mode 0)
			)
			(polygon
				(pts
					(xy 455.407522 -45.648626) (xy 448.333622 -45.648626) (xy 448.333622 -52.582826) (xy 449.438522 -52.582826)
					(xy 449.438522 -48.468026) (xy 454.061322 -48.468026) (xy 454.061322 -52.582826) (xy 455.407522 -52.582826)
				)
			)
		)
		(zone
			(layer "F.Cu")
			(hatch none 0.5)
			(connect_pads
				(clearance 0)
			)
			(min_thickness 0.25)
			(keepout
				(tracks allowed)
				(vias not_allowed)
				(pads allowed)
				(copperpour not_allowed)
				(footprints allowed)
			)
			(placement
				(enabled no)
				(sheetname "")
			)
			(fill
				(thermal_gap 0.5)
				(thermal_bridge_width 0.5)
				(island_removal_mode 0)
			)
			(polygon
				(pts
					(xy 455.407522 -12.171426) (xy 448.333622 -12.171426) (xy 448.333622 -5.237226) (xy 449.438522 -5.237226)
					(xy 449.438522 -9.352026) (xy 454.061322 -9.352026) (xy 454.061322 -5.237226) (xy 455.407522 -5.237226)
				)
			)
		)
		(zone
			(layer "F.Cu")
			(hatch none 0.5)
			(connect_pads
				(clearance 0)
			)
			(min_thickness 0.25)
			(keepout
				(tracks not_allowed)
				(vias allowed)
				(pads allowed)
				(copperpour not_allowed)
				(footprints allowed)
			)
			(placement
				(enabled no)
				(sheetname "")
			)
			(fill
				(thermal_gap 0.5)
				(thermal_bridge_width 0.5)
				(island_removal_mode 0)
			)
			(polygon
				(pts
					(xy 455.407522 -12.171426) (xy 448.333622 -12.171426) (xy 448.333622 -5.237226) (xy 449.438522 -5.237226)
					(xy 449.438522 -9.352026) (xy 454.061322 -9.352026) (xy 454.061322 -5.237226) (xy 455.407522 -5.237226)
				)
			)
		)
		(zone
			(layers "F.Cu" "B.Cu" "In1.Cu" "In2.Cu" "In3.Cu" "In4.Cu" "In5.Cu" "In6.Cu")
			(hatch none 0.5)
			(connect_pads
				(clearance 0)
			)
			(min_thickness 0.25)
			(keepout
				(tracks not_allowed)
				(vias allowed)
				(pads allowed)
				(copperpour not_allowed)
				(footprints allowed)
			)
			(placement
				(enabled no)
				(sheetname "")
			)
			(fill
				(thermal_gap 0.5)
				(thermal_bridge_width 0.5)
				(island_removal_mode 0)
			)
			(polygon
				(pts
					(arc
						(start 452.524622 -10.035032)
						(mid 450.975222 -10.035032)
						(end 452.524622 -10.035032)
					)
				)
			)
		)
		(zone
			(layers "F.Cu" "B.Cu" "In1.Cu" "In2.Cu" "In3.Cu" "In4.Cu" "In5.Cu" "In6.Cu")
			(hatch none 0.5)
			(connect_pads
				(clearance 0)
			)
			(min_thickness 0.25)
			(keepout
				(tracks not_allowed)
				(vias allowed)
				(pads allowed)
				(copperpour not_allowed)
				(footprints allowed)
			)
			(placement
				(enabled no)
				(sheetname "")
			)
			(fill
				(thermal_gap 0.5)
				(thermal_bridge_width 0.5)
				(island_removal_mode 0)
			)
			(polygon
				(pts
					(arc
						(start 452.727822 -47.78502)
						(mid 450.772022 -47.78502)
						(end 452.727822 -47.78502)
					)
				)
			)
		)
	)
)
